# T6G (Grand Teton) — schematic netlist excerpt (pin names and nets, part order shuffled) for the footprints in the layout excerpt that follows; sources: Cadence DE-HDL packaged netlist, KiCad conversion of 04192023_DAF0TMB3IC0_F0TG_MB_C_brd_V02_OCP.brd

J28  SCONN288_DDR506112002KQ  IO  pkg DDR288S_1-1VXC  page 100
  VIN_BULK0  = P12V_MEM_CPU1
  RFU0  = NC
  VIN_MGMT  = P3V3_AUX
  HSCL  = I3C_SPD_DDRC_CPU1_SCL
  HSDA  = I3C_SPD_DDRC_CPU1_SDA
  VSS0  = GND
  DQ0_A  = M_C_CPU1_SA_DQ<0>
  VSS1  = GND
  DQ1_A  = M_C_CPU1_SA_DQ<1>
  VSS2  = GND
  DQS0_A_T  = M_C_CPU1_SA_DQS_DP<0>
  DQS0_A_C  = M_C_CPU1_SA_DQS_DN<0>
  VSS3  = GND
  DQ4_A  = M_C_CPU1_SA_DQ<4>
  VSS4  = GND
  DQ5_A  = M_C_CPU1_SA_DQ<5>
  VSS5  = GND
  DQ8_A  = M_C_CPU1_SA_DQ<8>
  VSS6  = GND
  DQ9_A  = M_C_CPU1_SA_DQ<9>
  VSS7  = GND
  DQS1_A_T  = M_C_CPU1_SA_DQS_DP<1>
  DQS1_A_C  = M_C_CPU1_SA_DQS_DN<1>
  VSS8  = GND
  DQ12_A  = M_C_CPU1_SA_DQ<12>
  VSS9  = GND
  DQ13_A  = M_C_CPU1_SA_DQ<13>
  VSS10  = GND
  DQ16_A  = M_C_CPU1_SA_DQ<16>
  VSS11  = GND
  DQ17_A  = M_C_CPU1_SA_DQ<17>
  VSS12  = GND
  DQS2_A_T  = M_C_CPU1_SA_DQS_DP<2>
  DQS2_A_C  = M_C_CPU1_SA_DQS_DN<2>
  VSS13  = GND
  DQ20_A  = M_C_CPU1_SA_DQ<20>
  VSS14  = GND
  DQ21_A  = M_C_CPU1_SA_DQ<21>
  VSS15  = GND
  DQ24_A  = M_C_CPU1_SA_DQ<24>
  VSS16  = GND
  DQ25_A  = M_C_CPU1_SA_DQ<25>
  VSS17  = GND
  DQS3_A_T  = M_C_CPU1_SA_DQS_DP<3>
  DQS3_A_C  = M_C_CPU1_SA_DQS_DN<3>
  VSS18  = GND
  DQ28_A  = M_C_CPU1_SA_DQ<28>
  VSS19  = GND
  DQ29_A  = M_C_CPU1_SA_DQ<29>
  VSS20  = GND
  CB0_A  = M_C_CPU1_SA_CB<0>
  VSS21  = GND
  CB1_A  = M_C_CPU1_SA_CB<1>
  VSS22  = GND
  DQS4_A_T  = M_C_CPU1_SA_DQS_DP<4>
  DQS4_A_C  = M_C_CPU1_SA_DQS_DN<4>
  VSS23  = GND
  CB4_A  = M_C_CPU1_SA_CB<4>
  VSS24  = GND
  CB5_A  = M_C_CPU1_SA_CB<5>
  VSS25  = GND
  ALERT_N  = M_C_CPU1_ALERT_N
  VSS26  = GND
  CS0_A_N  = M_C_CPU1_SA_CS_N<0>
  VSS27  = GND
  CA0_A  = M_C_CPU1_SA_CA<0>
  VSS28  = GND
  CA2_A  = M_C_CPU1_SA_CA<2>
  VSS29  = GND
  CA4_A  = M_C_CPU1_SA_CA<4>
  VSS30  = GND
  CA6_A  = M_C_CPU1_SA_CA<6>
  VSS31  = GND
  PAR_A  = M_C_CPU1_SA_PAR
  VSS32  = GND
  CA0_B  = M_C_CPU1_SB_CA<0>
  VSS33  = GND
  CA2_B  = M_C_CPU1_SB_CA<2>
  VSS34  = GND
  CA4_B  = M_C_CPU1_SB_CA<4>
  VSS35  = GND
  CA6_B  = M_C_CPU1_SB_CA<6>
  VSS36  = GND
  CS0_B_N  = M_C_CPU1_SB_CS_N<0>
  VSS37  = GND
  \lbd||rsp_a_n\  = M_C_CPU1_SA_RSP<0>
  \lbs||rsp_b_n\  = M_C_CPU1_SB_RSP<0>
  VSS38  = GND
  CB4_B  = M_C_CPU1_SB_CB<4>
  VSS39  = GND
  CB5_B  = M_C_CPU1_SB_CB<5>
  VSS40  = GND
  \dqs9_b_t||tdqs9_b_t||dbi4_b_n\  = M_C_CPU1_SB_DQS_DP<9>
  \dqs9_b_c||tdqs9_b_c\  = M_C_CPU1_SB_DQS_DN<9>
  VSS41  = GND
  CB0_B  = M_C_CPU1_SB_CB<0>
  VSS42  = GND
  CB1_B  = M_C_CPU1_SB_CB<1>
  VSS43  = GND
  DQ0_B  = M_C_CPU1_SB_DQ<0>
  VSS44  = GND
  DQ1_B  = M_C_CPU1_SB_DQ<1>
  VSS45  = GND
  DQS0_B_T  = M_C_CPU1_SB_DQS_DP<0>
  DQS0_B_C  = M_C_CPU1_SB_DQS_DN<0>
  VSS46  = GND
  DQ4_B  = M_C_CPU1_SB_DQ<4>
  VSS47  = GND
  DQ5_B  = M_C_CPU1_SB_DQ<5>
  VSS48  = GND
  DQ8_B  = M_C_CPU1_SB_DQ<8>
  VSS49  = GND
  DQ9_B  = M_C_CPU1_SB_DQ<9>
  VSS50  = GND
  DQS1_B_T  = M_C_CPU1_SB_DQS_DP<1>
  DQS1_B_C  = M_C_CPU1_SB_DQS_DN<1>
  VSS51  = GND
  DQ12_B  = M_C_CPU1_SB_DQ<12>
  VSS52  = GND
  DQ13_B  = M_C_CPU1_SB_DQ<13>
  VSS53  = GND
  DQ16_B  = M_C_CPU1_SB_DQ<16>
  VSS54  = GND
  DQ17_B  = M_C_CPU1_SB_DQ<17>
  VSS55  = GND
  DQS2_B_T  = M_C_CPU1_SB_DQS_DP<2>
  DQS2_B_C  = M_C_CPU1_SB_DQS_DN<2>
  VSS56  = GND
  DQ20_B  = M_C_CPU1_SB_DQ<20>
  VSS57  = GND
  DQ21_B  = M_C_CPU1_SB_DQ<21>
  VSS58  = GND
  DQ24_B  = M_C_CPU1_SB_DQ<24>
  VSS59  = GND
  DQ25_B  = M_C_CPU1_SB_DQ<25>
  VSS60  = GND
  DQS3_B_T  = M_C_CPU1_SB_DQS_DP<3>
  DQS3_B_C  = M_C_CPU1_SB_DQS_DN<3>
  VSS61  = GND
  DQ28_B  = M_C_CPU1_SB_DQ<28>
  VSS62  = GND
  DQ29_B  = M_C_CPU1_SB_DQ<29>
  VSS63  = GND
  RFU1  = NC
  VIN_BULK1  = P12V_MEM_CPU1
  VIN_BULK2  = P12V_MEM_CPU1
  \pwr_good||fail_n\  = PWRGD_CHC_CPU1_DIMM
  HAS  = PD_CHC_CPU1_DIMM_SAA
  RFU2  = NC
  RFU3  = NC
  VSS64  = GND
  DQ2_A  = M_C_CPU1_SA_DQ<2>
  VSS65  = GND
  DQ3_A  = M_C_CPU1_SA_DQ<3>
  VSS66  = GND
  \dqs5_a_c||tdqs5_a_c||dqs5_a_t||tdqs5_a_t\  = M_C_CPU1_SA_DQS_DN<5>
  \dqs5_a_t||tdqs5_a_t\  = M_C_CPU1_SA_DQS_DP<5>
  VSS67  = GND
  DQ6_A  = M_C_CPU1_SA_DQ<6>
  VSS68  = GND
  DQ7_A  = M_C_CPU1_SA_DQ<7>
  VSS69  = GND
  DQ10_A  = M_C_CPU1_SA_DQ<10>
  VSS70  = GND
  DQ11_A  = M_C_CPU1_SA_DQ<11>
  VSS71  = GND
  \dqs6_a_c||tdqs6_a_c||dqs6_a_t||tdqs6_a_t\  = M_C_CPU1_SA_DQS_DN<6>
  \dqs6_a_t||tdqs6_a_t\  = M_C_CPU1_SA_DQS_DP<6>
  VSS72  = GND
  DQ14_A  = M_C_CPU1_SA_DQ<14>
  VSS73  = GND
  DQ15_A  = M_C_CPU1_SA_DQ<15>
  VSS74  = GND
  DQ18_A  = M_C_CPU1_SA_DQ<18>
  VSS75  = GND
  DQ19_A  = M_C_CPU1_SA_DQ<19>
  VSS76  = GND
  \dqs7_a_c||tdqs7_a_c\  = M_C_CPU1_SA_DQS_DN<7>
  \dqs7_a_t||tdqs7_a_t\  = M_C_CPU1_SA_DQS_DP<7>
  VSS77  = GND
  DQ22_A  = M_C_CPU1_SA_DQ<22>
  VSS78  = GND
  DQ23_A  = M_C_CPU1_SA_DQ<23>
  VSS79  = GND
  DQ26_A  = M_C_CPU1_SA_DQ<26>
  VSS80  = GND
  DQ27_A  = M_C_CPU1_SA_DQ<27>
  VSS81  = GND
  \dqs8_a_c||tdqs8_a_c\  = M_C_CPU1_SA_DQS_DN<8>
  \dqs8_a_t||tdqs8_a_t\  = M_C_CPU1_SA_DQS_DP<8>
  VSS82  = GND
  DQ30_A  = M_C_CPU1_SA_DQ<30>
  VSS83  = GND
  DQ31_A  = M_C_CPU1_SA_DQ<31>
  VSS84  = GND
  CB2_A  = M_C_CPU1_SA_CB<2>
  VSS85  = GND
  CB3_A  = M_C_CPU1_SA_CB<3>
  VSS86  = GND
  \dqs9_a_c||tdqs9_a_c\  = M_C_CPU1_SA_DQS_DN<9>
  \dqs9_a_t||tdqs9_a_t\  = M_C_CPU1_SA_DQS_DP<9>
  VSS87  = GND
  CB6_A  = M_C_CPU1_SA_CB<6>
  VSS88  = GND
  CB7_A  = M_C_CPU1_SA_CB<7>
  VSS89  = GND
  RESET_N  = M_C_CPU1_RESET_N
  VSS90  = GND
  CS1_A_N  = M_C_CPU1_SA_CS_N<1>
  VSS91  = GND
  CA1_A  = M_C_CPU1_SA_CA<1>
  VSS92  = GND
  CA3_A  = M_C_CPU1_SA_CA<3>
  VSS93  = GND
  CA5_A  = M_C_CPU1_SA_CA<5>
  VSS94  = GND
  CK_T  = M_C_CPU1_CLK_DP<0>
  CK_C  = M_C_CPU1_CLK_DN<0>
  VSS95  = GND
  RFU4  = NC
  CA1_B  = M_C_CPU1_SB_CA<1>
  VSS96  = GND
  CA3_B  = M_C_CPU1_SB_CA<3>
  VSS97  = GND
  CA5_B  = M_C_CPU1_SB_CA<5>
  VSS98  = GND
  PAR_B  = M_C_CPU1_SB_PAR
  VSS99  = GND
  CS1_B_N  = M_C_CPU1_SB_CS_N<1>
  VSS100  = GND
  RFU5  = NC
  RFU6  = NC
  VSS101  = GND
  CB6_B  = M_C_CPU1_SB_CB<6>
  VSS102  = GND
  CB7_B  = M_C_CPU1_SB_CB<7>
  VSS103  = GND
  DQS4_B_C  = M_C_CPU1_SB_DQS_DN<4>
  DQS4_B_T  = M_C_CPU1_SB_DQS_DP<4>
  VSS104  = GND
  CB2_B  = M_C_CPU1_SB_CB<2>
  VSS105  = GND
  CB3_B  = M_C_CPU1_SB_CB<3>
  VSS106  = GND
  DQ2_B  = M_C_CPU1_SB_DQ<2>
  VSS107  = GND
  DQ3_B  = M_C_CPU1_SB_DQ<3>
  VSS108  = GND
  \dqs5_b_c||tdqs5_b_c\  = M_C_CPU1_SB_DQS_DN<5>
  \dqs5_b_t||tdqs5_b_t\  = M_C_CPU1_SB_DQS_DP<5>
  VSS109  = GND
  DQ6_B  = M_C_CPU1_SB_DQ<6>
  VSS110  = GND
  DQ7_B  = M_C_CPU1_SB_DQ<7>
  VSS111  = GND
  DQ10_B  = M_C_CPU1_SB_DQ<10>
  VSS112  = GND
  DQ11_B  = M_C_CPU1_SB_DQ<11>
  VSS113  = GND
  \dqs6_b_c||tdqs6_b_c\  = M_C_CPU1_SB_DQS_DN<6>
  \dqs6_b_t||tdqs6_b_t\  = M_C_CPU1_SB_DQS_DP<6>
  VSS114  = GND
  DQ14_B  = M_C_CPU1_SB_DQ<14>
  VSS115  = GND
  DQ15_B  = M_C_CPU1_SB_DQ<15>
  VSS116  = GND
  DQ18_B  = M_C_CPU1_SB_DQ<18>
  VSS117  = GND
  DQ19_B  = M_C_CPU1_SB_DQ<19>
  VSS118  = GND
  \dqs7_b_c||tdqs7_b_c\  = M_C_CPU1_SB_DQS_DN<7>
  \dqs7_b_t||tdqs7_b_t\  = M_C_CPU1_SB_DQS_DP<7>
  VSS119  = GND
  DQ22_B  = M_C_CPU1_SB_DQ<22>
  VSS120  = GND
  DQ23_B  = M_C_CPU1_SB_DQ<23>
  VSS121  = GND
  DQ26_B  = M_C_CPU1_SB_DQ<26>
  VSS122  = GND
  DQ27_B  = M_C_CPU1_SB_DQ<27>
  VSS123  = GND
  \dqs8_b_c||tdqs8_b_c\  = M_C_CPU1_SB_DQS_DN<8>
  \dqs8_b_t||tdqs8_b_t\  = M_C_CPU1_SB_DQS_DP<8>
  VSS124  = GND
  DQ30_B  = M_C_CPU1_SB_DQ<30>
  VSS125  = GND
  DQ31_B  = M_C_CPU1_SB_DQ<31>
  VSS126  = GND
  G1  = GND
  G2  = GND
  G3  = GND

(kicad_pcb
	(version 20260206)
	(generator "pcbnew")
	(generator_version "10.0")
	(general
		(thickness 1.6)
		(legacy_teardrops no)
	)
	(paper "A4")
	(title_block
		(title "04192023_DAF0TMB3IC0_F0TG_MB_C_brd_V02_OCP.brd")
		(comment 1 "Grand Teton / footprint 4188 of 8354 (J28), pads 93-138 of 291")
	)
	(layers
		(0 "F.Cu" signal "TOP")
		(4 "In1.Cu" signal "GND")
		(6 "In2.Cu" signal "IN1")
		(8 "In3.Cu" signal "GND1")
		(10 "In4.Cu" signal "IN2")
		(12 "In5.Cu" signal "GND2")
		(14 "In6.Cu" signal "IN3")
		(16 "In7.Cu" signal "GND3")
		(18 "In8.Cu" signal "VCC")
		(20 "In9.Cu" signal "VCC1")
		(22 "In10.Cu" signal "GND4")
		(24 "In11.Cu" signal "IN4")
		(26 "In12.Cu" signal "GND5")
		(28 "In13.Cu" signal "IN5")
		(30 "In14.Cu" signal "GND6")
		(32 "In15.Cu" signal "IN6")
		(34 "In16.Cu" signal "GND7")
		(2 "B.Cu" signal "BOTTOM")
		(9 "F.Adhes" user "F.Adhesive")
		(11 "B.Adhes" user "B.Adhesive")
		(13 "F.Paste" user "Package Geometry/Pastemask Top")
		(15 "B.Paste" user "Package Geometry/Pastemask Bottom")
		(5 "F.SilkS" user "Ref Des/Silkscreen Top")
		(7 "B.SilkS" user "Ref Des/Silkscreen Bottom")
		(1 "F.Mask" user "Board Geometry/Soldermask Top")
		(3 "B.Mask" user "Board Geometry/Soldermask Bottom")
		(17 "Dwgs.User" user "User.Drawings")
		(19 "Cmts.User" user "User.Comments")
		(21 "Eco1.User" user "User.Eco1")
		(23 "Eco2.User" user "User.Eco2")
		(25 "Edge.Cuts" user "Board Geometry/Outline")
		(27 "Margin" user)
		(31 "F.CrtYd" user "Package Geometry/Place Bound Top")
		(29 "B.CrtYd" user "Package Geometry/Place Bound Bottom")
		(35 "F.Fab" user "Ref Des/Assembly Top")
		(33 "B.Fab" user "Ref Des/Assembly Bottom")
	)
	(footprint ""
		(layer "F.Cu")
		(at 42.289984 -255.560322 180)
		(property "Reference" "J28"
			(at -2.876296 -82.230976 0)
			(unlocked yes)
			(layer "F.SilkS")
			(effects
				(font
					(size 0.7874 0.5842)
					(thickness 0.1524)
				)
			)
		)
		(property "Value" ""
			(at 0 0 180)
			(layer "F.Fab")
			(effects
				(font
					(size 1.27 1.27)
				)
			)
		)
		(duplicate_pad_numbers_are_jumpers no)
		(pad "93" smd rect
			(at -2.050034 19.975068 90)
			(size 0.519938 1.4986)
			(layers "F.Cu" "F.Mask" "F.Paste")
			(net "M_C_CPU1_SB_DQS_DP<9>")
		)
		(pad "94" smd rect
			(at -2.050034 20.824952 90)
			(size 0.519938 1.4986)
			(layers "F.Cu" "F.Mask" "F.Paste")
			(net "M_C_CPU1_SB_DQS_DN<9>")
		)
		(pad "95" smd rect
			(at -2.050034 21.67509 90)
			(size 0.519938 1.4986)
			(layers "F.Cu" "F.Mask" "F.Paste")
			(net "GND")
		)
		(pad "96" smd rect
			(at -2.050034 22.524974 90)
			(size 0.519938 1.4986)
			(layers "F.Cu" "F.Mask" "F.Paste")
			(net "M_C_CPU1_SB_CB<0>")
		)
		(pad "97" smd rect
			(at -2.050034 23.375112 90)
			(size 0.519938 1.4986)
			(layers "F.Cu" "F.Mask" "F.Paste")
			(net "GND")
		)
		(pad "98" smd rect
			(at -2.050034 24.224996 90)
			(size 0.519938 1.4986)
			(layers "F.Cu" "F.Mask" "F.Paste")
			(net "M_C_CPU1_SB_CB<1>")
		)
		(pad "99" smd rect
			(at -2.050034 25.07488 90)
			(size 0.519938 1.4986)
			(layers "F.Cu" "F.Mask" "F.Paste")
			(net "GND")
		)
		(pad "100" smd rect
			(at -2.050034 25.925018 90)
			(size 0.519938 1.4986)
			(layers "F.Cu" "F.Mask" "F.Paste")
			(net "M_C_CPU1_SB_DQ<0>")
		)
		(pad "101" smd rect
			(at -2.050034 26.774902 90)
			(size 0.519938 1.4986)
			(layers "F.Cu" "F.Mask" "F.Paste")
			(net "GND")
		)
		(pad "102" smd rect
			(at -2.050034 27.62504 90)
			(size 0.519938 1.4986)
			(layers "F.Cu" "F.Mask" "F.Paste")
			(net "M_C_CPU1_SB_DQ<1>")
		)
		(pad "103" smd rect
			(at -2.050034 28.474924 90)
			(size 0.519938 1.4986)
			(layers "F.Cu" "F.Mask" "F.Paste")
			(net "GND")
		)
		(pad "104" smd rect
			(at -2.050034 29.325062 90)
			(size 0.519938 1.4986)
			(layers "F.Cu" "F.Mask" "F.Paste")
			(net "M_C_CPU1_SB_DQS_DP<0>")
		)
		(pad "105" smd rect
			(at -2.050034 30.174946 90)
			(size 0.519938 1.4986)
			(layers "F.Cu" "F.Mask" "F.Paste")
			(net "M_C_CPU1_SB_DQS_DN<0>")
		)
		(pad "106" smd rect
			(at -2.050034 31.025084 90)
			(size 0.519938 1.4986)
			(layers "F.Cu" "F.Mask" "F.Paste")
			(net "GND")
		)
		(pad "107" smd rect
			(at -2.050034 31.874968 90)
			(size 0.519938 1.4986)
			(layers "F.Cu" "F.Mask" "F.Paste")
			(net "M_C_CPU1_SB_DQ<4>")
		)
		(pad "108" smd rect
			(at -2.050034 32.725106 90)
			(size 0.519938 1.4986)
			(layers "F.Cu" "F.Mask" "F.Paste")
			(net "GND")
		)
		(pad "109" smd rect
			(at -2.050034 33.57499 90)
			(size 0.519938 1.4986)
			(layers "F.Cu" "F.Mask" "F.Paste")
			(net "M_C_CPU1_SB_DQ<5>")
		)
		(pad "110" smd rect
			(at -2.050034 34.425128 90)
			(size 0.519938 1.4986)
			(layers "F.Cu" "F.Mask" "F.Paste")
			(net "GND")
		)
		(pad "111" smd rect
			(at -2.050034 35.275012 90)
			(size 0.519938 1.4986)
			(layers "F.Cu" "F.Mask" "F.Paste")
			(net "M_C_CPU1_SB_DQ<8>")
		)
		(pad "112" smd rect
			(at -2.050034 36.124896 90)
			(size 0.519938 1.4986)
			(layers "F.Cu" "F.Mask" "F.Paste")
			(net "GND")
		)
		(pad "113" smd rect
			(at -2.050034 36.975034 90)
			(size 0.519938 1.4986)
			(layers "F.Cu" "F.Mask" "F.Paste")
			(net "M_C_CPU1_SB_DQ<9>")
		)
		(pad "114" smd rect
			(at -2.050034 37.824918 90)
			(size 0.519938 1.4986)
			(layers "F.Cu" "F.Mask" "F.Paste")
			(net "GND")
		)
		(pad "115" smd rect
			(at -2.050034 38.675056 90)
			(size 0.519938 1.4986)
			(layers "F.Cu" "F.Mask" "F.Paste")
			(net "M_C_CPU1_SB_DQS_DP<1>")
		)
		(pad "116" smd rect
			(at -2.050034 39.52494 90)
			(size 0.519938 1.4986)
			(layers "F.Cu" "F.Mask" "F.Paste")
			(net "M_C_CPU1_SB_DQS_DN<1>")
		)
		(pad "117" smd rect
			(at -2.050034 40.375078 90)
			(size 0.519938 1.4986)
			(layers "F.Cu" "F.Mask" "F.Paste")
			(net "GND")
		)
		(pad "118" smd rect
			(at -2.050034 41.224962 90)
			(size 0.519938 1.4986)
			(layers "F.Cu" "F.Mask" "F.Paste")
			(net "M_C_CPU1_SB_DQ<12>")
		)
		(pad "119" smd rect
			(at -2.050034 42.0751 90)
			(size 0.519938 1.4986)
			(layers "F.Cu" "F.Mask" "F.Paste")
			(net "GND")
		)
		(pad "120" smd rect
			(at -2.050034 42.924984 90)
			(size 0.519938 1.4986)
			(layers "F.Cu" "F.Mask" "F.Paste")
			(net "M_C_CPU1_SB_DQ<13>")
		)
		(pad "121" smd rect
			(at -2.050034 43.775122 90)
			(size 0.519938 1.4986)
			(layers "F.Cu" "F.Mask" "F.Paste")
			(net "GND")
		)
		(pad "122" smd rect
			(at -2.050034 44.625006 90)
			(size 0.519938 1.4986)
			(layers "F.Cu" "F.Mask" "F.Paste")
			(net "M_C_CPU1_SB_DQ<16>")
		)
		(pad "123" smd rect
			(at -2.050034 45.47489 90)
			(size 0.519938 1.4986)
			(layers "F.Cu" "F.Mask" "F.Paste")
			(net "GND")
		)
		(pad "124" smd rect
			(at -2.050034 46.325028 90)
			(size 0.519938 1.4986)
			(layers "F.Cu" "F.Mask" "F.Paste")
			(net "M_C_CPU1_SB_DQ<17>")
		)
		(pad "125" smd rect
			(at -2.050034 47.174912 90)
			(size 0.519938 1.4986)
			(layers "F.Cu" "F.Mask" "F.Paste")
			(net "GND")
		)
		(pad "126" smd rect
			(at -2.050034 48.02505 90)
			(size 0.519938 1.4986)
			(layers "F.Cu" "F.Mask" "F.Paste")
			(net "M_C_CPU1_SB_DQS_DP<2>")
		)
		(pad "127" smd rect
			(at -2.050034 48.874934 90)
			(size 0.519938 1.4986)
			(layers "F.Cu" "F.Mask" "F.Paste")
			(net "M_C_CPU1_SB_DQS_DN<2>")
		)
		(pad "128" smd rect
			(at -2.050034 49.725072 90)
			(size 0.519938 1.4986)
			(layers "F.Cu" "F.Mask" "F.Paste")
			(net "GND")
		)
		(pad "129" smd rect
			(at -2.050034 50.574956 90)
			(size 0.519938 1.4986)
			(layers "F.Cu" "F.Mask" "F.Paste")
			(net "M_C_CPU1_SB_DQ<20>")
		)
		(pad "130" smd rect
			(at -2.050034 51.425094 90)
			(size 0.519938 1.4986)
			(layers "F.Cu" "F.Mask" "F.Paste")
			(net "GND")
		)
		(pad "131" smd rect
			(at -2.050034 52.274978 90)
			(size 0.519938 1.4986)
			(layers "F.Cu" "F.Mask" "F.Paste")
			(net "M_C_CPU1_SB_DQ<21>")
		)
		(pad "132" smd rect
			(at -2.050034 53.125116 90)
			(size 0.519938 1.4986)
			(layers "F.Cu" "F.Mask" "F.Paste")
			(net "GND")
		)
		(pad "133" smd rect
			(at -2.050034 53.975 90)
			(size 0.519938 1.4986)
			(layers "F.Cu" "F.Mask" "F.Paste")
			(net "M_C_CPU1_SB_DQ<24>")
		)
		(pad "134" smd rect
			(at -2.050034 54.824884 90)
			(size 0.519938 1.4986)
			(layers "F.Cu" "F.Mask" "F.Paste")
			(net "GND")
		)
		(pad "135" smd rect
			(at -2.050034 55.675022 90)
			(size 0.519938 1.4986)
			(layers "F.Cu" "F.Mask" "F.Paste")
			(net "M_C_CPU1_SB_DQ<25>")
		)
		(pad "136" smd rect
			(at -2.050034 56.524906 90)
			(size 0.519938 1.4986)
			(layers "F.Cu" "F.Mask" "F.Paste")
			(net "GND")
		)
		(pad "137" smd rect
			(at -2.050034 57.375044 90)
			(size 0.519938 1.4986)
			(layers "F.Cu" "F.Mask" "F.Paste")
			(net "M_C_CPU1_SB_DQS_DP<3>")
		)
		(pad "138" smd rect
			(at -2.050034 58.224928 90)
			(size 0.519938 1.4986)
			(layers "F.Cu" "F.Mask" "F.Paste")
			(net "M_C_CPU1_SB_DQS_DN<3>")
		)
	)
)
